FILE_TYPE = CONNECTIVITY;
{Allegro Design Entry HDL 17.2-2016 S081 (4005846) 1/11/2022}
"PAGE_NUMBER" = 108;
0"NC";
1"P3V3_AUX\g";
2"P12V_S3_AUX_CPU1_NVDIMM\g";
3"P12V_S3_AUX_CPU1_NVDIMM\g";
4"P3V3_AUX\g";
5"GND\g";
6"GND\g";
7"GND\g";
8"GND\g";
9"GND\g";
10"M_F_CPU1_SA_DQ<31:0>";
11"M_F_CPU1_SA_CB<7:0>";
12"M_F_CPU1_SA_CA<6:0>";
13"M_F_CPU1_SB_CA<6:0>";
14"M_F_CPU1_SB_CB<7:0>";
15"M_F_CPU1_SB_DQ<31:0>";
16"M_F_CPU1_SB_DQS_DP<9:0>";
17"M_F_CPU1_SA_DQS_DP<9:0>";
18"M_F_CPU1_SB_DQS_DN<9:0>";
19"M_F_CPU1_SA_DQS_DN<9:0>";
20"I3C_SPD_DDREFGH_CPU1_LVC1_SDA";
21"I3C_SPD_DDREFGH_CPU1_LVC1_SCL_R3";
22"PD_CHF_CPU1_DIMM1_SAA";
23"RST_M_EF_CPU1_FPGA_N";
24"M_F_CPU1_ALERT_N";
25"I3C_SPD_DDREFGH_CPU1_LVC1_SCL";
26"PWRGD_CHF_CPU1_DIMM1";
27"TP_CHF_CPU1_DIMM1_FRU_6";
28"M_F_CPU1_SB_DQS_DP<8>";
29"M_F_CPU1_SB_DQS_DN<8>";
30"M_F_CPU1_SA_DQS_DN<9>";
31"M_F_CPU1_SA_DQS_DN<8>";
32"M_F_CPU1_SA_DQS_DN<7>";
33"M_F_CPU1_SA_DQS_DN<6>";
34"M_F_CPU1_SA_DQS_DN<5>";
35"M_F_CPU1_SA_DQS_DN<4>";
36"M_F_CPU1_SA_DQS_DN<3>";
37"M_F_CPU1_SA_DQS_DN<0>";
38"M_F_CPU1_SA_DQS_DN<1>";
39"M_F_CPU1_SA_DQS_DN<2>";
40"M_F_CPU1_SB_DQS_DN<9>";
41"M_F_CPU1_SB_DQS_DN<7>";
42"M_F_CPU1_SB_DQS_DN<6>";
43"M_F_CPU1_SB_DQS_DN<5>";
44"M_F_CPU1_SB_DQS_DN<4>";
45"M_F_CPU1_SB_DQS_DN<3>";
46"M_F_CPU1_SB_DQS_DN<0>";
47"M_F_CPU1_SB_DQS_DN<2>";
48"M_F_CPU1_SB_DQS_DN<1>";
49"M_F_CPU1_SA_DQS_DP<7>";
50"M_F_CPU1_SA_DQS_DP<8>";
51"M_F_CPU1_SA_DQS_DP<9>";
52"M_F_CPU1_SA_DQS_DP<5>";
53"M_F_CPU1_SA_DQS_DP<6>";
54"M_F_CPU1_SA_DQS_DP<4>";
55"M_F_CPU1_SA_DQS_DP<3>";
56"M_F_CPU1_SA_DQS_DP<2>";
57"M_F_CPU1_SA_DQS_DP<0>";
58"M_F_CPU1_SA_DQS_DP<1>";
59"M_F_CPU1_SB_DQS_DP<9>";
60"M_F_CPU1_SB_DQS_DP<7>";
61"M_F_CPU1_SB_DQS_DP<6>";
62"M_F_CPU1_SB_DQS_DP<5>";
63"M_F_CPU1_SB_DQS_DP<4>";
64"M_F_CPU1_SB_DQS_DP<3>";
65"M_F_CPU1_SB_DQS_DP<2>";
66"M_F_CPU1_SB_DQS_DP<0>";
67"M_F_CPU1_SB_DQS_DP<1>";
68"M_F_CPU1_SA_CB<1>";
69"TP_CHF_CPU1_DIMM1_FRU_1";
70"TP_CHF_CPU1_DIMM1_FRU_3";
71"M_F_CPU1_SA_RSP<0>";
72"TP_CHF_CPU1_DIMM1_FRU_0";
73"TP_CHF_CPU1_DIMM1_FRU_5";
74"M_F_CPU1_SB_CB<7>";
75"M_F_CPU1_SA_DQ<13>";
76"M_F_CPU1_SA_DQ<28>";
77"M_F_CPU1_SA_DQ<20>";
78"M_F_CPU1_SA_DQ<19>";
79"M_F_CPU1_SB_DQ<17>";
80"TP_CHF_CPU1_DIMM1_FRU_2";
81"TP_CHF_CPU1_DIMM1_FRU_4";
82"M_F_CPU1_SB_PAR";
83"M_F_CPU1_SA_PAR";
84"M_F_CPU1_SB_RSP<0>";
85"M_F_CPU1_SB_DQ<0>";
86"M_F_CPU1_SB_DQ<1>";
87"M_F_CPU1_SB_DQ<2>";
88"M_F_CPU1_SB_DQ<3>";
89"M_F_CPU1_SB_DQ<4>";
90"M_F_CPU1_SB_DQ<5>";
91"M_F_CPU1_SB_DQ<6>";
92"M_F_CPU1_SB_DQ<7>";
93"M_F_CPU1_SB_DQ<8>";
94"M_F_CPU1_SB_DQ<9>";
95"M_F_CPU1_SB_DQ<10>";
96"M_F_CPU1_SB_DQ<11>";
97"M_F_CPU1_SB_DQ<12>";
98"M_F_CPU1_SB_DQ<13>";
99"M_F_CPU1_SB_DQ<14>";
100"M_F_CPU1_SB_DQ<15>";
101"M_F_CPU1_SB_DQ<16>";
102"M_F_CPU1_SB_DQ<18>";
103"M_F_CPU1_SB_DQ<19>";
104"M_F_CPU1_SB_DQ<20>";
105"M_F_CPU1_SB_DQ<21>";
106"M_F_CPU1_SB_DQ<22>";
107"M_F_CPU1_SB_DQ<23>";
108"M_F_CPU1_SB_DQ<24>";
109"M_F_CPU1_SB_DQ<25>";
110"M_F_CPU1_SB_DQ<26>";
111"M_F_CPU1_SB_DQ<27>";
112"M_F_CPU1_SB_DQ<28>";
113"M_F_CPU1_SB_DQ<29>";
114"M_F_CPU1_SB_DQ<30>";
115"M_F_CPU1_SB_DQ<31>";
116"M_F_CPU1_SA_DQ<0>";
117"M_F_CPU1_SA_DQ<1>";
118"M_F_CPU1_SA_DQ<2>";
119"M_F_CPU1_SA_DQ<3>";
120"M_F_CPU1_SA_DQ<4>";
121"M_F_CPU1_SA_DQ<5>";
122"M_F_CPU1_SA_DQ<6>";
123"M_F_CPU1_SA_DQ<7>";
124"M_F_CPU1_SA_DQ<8>";
125"M_F_CPU1_SA_DQ<9>";
126"M_F_CPU1_SA_DQ<10>";
127"M_F_CPU1_SA_DQ<11>";
128"M_F_CPU1_SA_DQ<12>";
129"M_F_CPU1_SA_DQ<14>";
130"M_F_CPU1_SA_DQ<15>";
131"M_F_CPU1_SA_DQ<16>";
132"M_F_CPU1_SA_DQ<17>";
133"M_F_CPU1_SA_DQ<18>";
134"M_F_CPU1_SA_DQ<21>";
135"M_F_CPU1_SA_DQ<22>";
136"M_F_CPU1_SA_DQ<23>";
137"M_F_CPU1_SA_DQ<24>";
138"M_F_CPU1_SA_DQ<25>";
139"M_F_CPU1_SA_DQ<26>";
140"M_F_CPU1_SA_DQ<27>";
141"M_F_CPU1_SA_DQ<29>";
142"M_F_CPU1_SA_DQ<30>";
143"M_F_CPU1_SB_CS_N<1>";
144"M_F_CPU1_SA_CS_N<1>";
145"M_F_CPU1_SB_CS_N<0>";
146"M_F_CPU1_SA_CS_N<0>";
147"M_F_CPU1_CLK_DP<0>";
148"M_F_CPU1_CLK_DN<0>";
149"M_F_CPU1_SB_CB<0>";
150"M_F_CPU1_SB_CB<1>";
151"M_F_CPU1_SB_CB<2>";
152"M_F_CPU1_SB_CB<3>";
153"M_F_CPU1_SB_CB<4>";
154"M_F_CPU1_SB_CB<5>";
155"M_F_CPU1_SB_CB<6>";
156"M_F_CPU1_SA_CB<0>";
157"M_F_CPU1_SA_CB<2>";
158"M_F_CPU1_SA_CB<3>";
159"M_F_CPU1_SA_CB<5>";
160"M_F_CPU1_SA_CB<6>";
161"M_F_CPU1_SB_CA<6>";
162"M_F_CPU1_SA_CA<6>";
163"M_F_CPU1_SB_CA<5>";
164"M_F_CPU1_SA_CA<5>";
165"M_F_CPU1_SB_CA<4>";
166"M_F_CPU1_SA_CA<4>";
167"M_F_CPU1_SB_CA<3>";
168"M_F_CPU1_SA_CA<3>";
169"M_F_CPU1_SB_CA<2>";
170"M_F_CPU1_SA_CA<2>";
171"M_F_CPU1_SB_CA<1>";
172"M_F_CPU1_SA_CA<1>";
173"M_F_CPU1_SB_CA<0>";
174"M_F_CPU1_SA_CA<0>";
175"M_F_CPU1_SA_CB<4>";
176"M_F_CPU1_SA_CB<7>";
177"M_F_CPU1_SA_DQ<31>";
178"PD_CHF_CPU1_DIMM1_SAA";
%"Q_RES"
"2","(-2500,1200)","0","pure_quanta","I10";
;
PART_NUMBER"CS32322FB03"
VALUE"23.2K"
WATTAGE"1/16W"
MATERIAL"CHIP"
PACK_TYPE"0402LF"
TOLERANCE"1%"
$LOCATION"R77"
CDS_LIB"pure_quanta"
$LOCATION"R77"
CDS_LOCATION"R77"
$SEC"1"
CDS_SEC"1";
"A"
$PN"1"178;
"B"
$PN"2"9;
%"TAP"
"1","(-1075,4900)","0","standard","I100";
;
CDS_LIB"standard"
BODY_TYPE"PLUMBING"
HDL_TAP"TRUE";
"B \NAC \NWC"10;
"S \NAC"
BN"22"135;
%"TAP"
"1","(-1075,5000)","0","standard","I101";
;
CDS_LIB"standard"
BODY_TYPE"PLUMBING"
HDL_TAP"TRUE";
"B \NAC \NWC"10;
"S \NAC"
BN"24"137;
%"TAP"
"1","(-1075,4950)","0","standard","I102";
;
CDS_LIB"standard"
BODY_TYPE"PLUMBING"
HDL_TAP"TRUE";
"B \NAC \NWC"10;
"S \NAC"
BN"23"136;
%"TAP"
"1","(-2725,5100)","2","standard","I105";
;
CDS_LIB"standard"
BODY_TYPE"PLUMBING"
HDL_TAP"TRUE";
"B \NAC \NWC"12;
"S \NAC"
BN"1"172;
%"TAP"
"1","(-2725,5050)","2","standard","I106";
;
CDS_LIB"standard"
BODY_TYPE"PLUMBING"
HDL_TAP"TRUE";
"B \NAC \NWC"12;
"S \NAC"
BN"0"174;
%"TAP"
"1","(-2725,5150)","2","standard","I107";
;
CDS_LIB"standard"
BODY_TYPE"PLUMBING"
HDL_TAP"TRUE";
"B \NAC \NWC"12;
"S \NAC"
BN"2"170;
%"TAP"
"1","(-2725,5200)","2","standard","I108";
;
CDS_LIB"standard"
BODY_TYPE"PLUMBING"
HDL_TAP"TRUE";
"B \NAC \NWC"12;
"S \NAC"
BN"3"168;
%"TAP"
"1","(-2725,5250)","2","standard","I109";
;
CDS_LIB"standard"
BODY_TYPE"PLUMBING"
HDL_TAP"TRUE";
"B \NAC \NWC"12;
"S \NAC"
BN"4"166;
%"TAP"
"1","(-2725,5300)","2","standard","I110";
;
CDS_LIB"standard"
BODY_TYPE"PLUMBING"
HDL_TAP"TRUE";
"B \NAC \NWC"12;
"S \NAC"
BN"5"164;
%"TAP"
"1","(-2725,5350)","2","standard","I111";
;
CDS_LIB"standard"
BODY_TYPE"PLUMBING"
HDL_TAP"TRUE";
"B \NAC \NWC"12;
"S \NAC"
BN"6"162;
%"TAP"
"1","(-1075,5050)","0","standard","I112";
;
CDS_LIB"standard"
BODY_TYPE"PLUMBING"
HDL_TAP"TRUE";
"B \NAC \NWC"10;
"S \NAC"
BN"25"138;
%"TAP"
"1","(-1075,5100)","0","standard","I113";
;
CDS_LIB"standard"
BODY_TYPE"PLUMBING"
HDL_TAP"TRUE";
"B \NAC \NWC"10;
"S \NAC"
BN"26"139;
%"TAP"
"1","(-1075,5150)","0","standard","I114";
;
CDS_LIB"standard"
BODY_TYPE"PLUMBING"
HDL_TAP"TRUE";
"B \NAC \NWC"10;
"S \NAC"
BN"27"140;
%"TAP"
"1","(-1075,5200)","0","standard","I115";
;
CDS_LIB"standard"
BODY_TYPE"PLUMBING"
HDL_TAP"TRUE";
"B \NAC \NWC"10;
"S \NAC"
BN"28"76;
%"TAP"
"1","(-1075,5300)","0","standard","I116";
;
CDS_LIB"standard"
BODY_TYPE"PLUMBING"
HDL_TAP"TRUE";
"B \NAC \NWC"10;
"S \NAC"
BN"30"142;
%"TAP"
"1","(-1075,5250)","0","standard","I117";
;
CDS_LIB"standard"
BODY_TYPE"PLUMBING"
HDL_TAP"TRUE";
"B \NAC \NWC"10;
"S \NAC"
BN"29"141;
%"TAP"
"1","(-1075,5350)","0","standard","I118";
;
CDS_LIB"standard"
BODY_TYPE"PLUMBING"
HDL_TAP"TRUE";
"B \NAC \NWC"10;
"S \NAC"
BN"31"177;
%"UNIVERSAL_GND"
"1","(650,1100)","0","logical_power","I120";
;
HDL_POWER"GND"
CDS_LIB"logical_power";
"A"5;
%"Q_CAP"
"1","(650,1475)","0","pure_quanta","I121";
;
PART_NUMBER"CH5221MEB00"
VALUE"2.2UF"
PACK_TYPE"C0402"
TOLERANCE"20%"
VOLTAGE"6.3V"
MATERIAL"X6S"
$LOCATION"C87"
CDS_LIB"pure_quanta"
$LOCATION"C87"
CDS_LOCATION"C87"
$SEC"1"
CDS_SEC"1";
"B"
$PN"2"5;
"A"
$PN"1"1;
%"VCC_CORE"
"1","(650,1800)","0","logical_power","I122";
;
HDL_POWER"P3V3_AUX"
CDS_LIB"logical_power";
"A"1;
%"Q_CAP"
"1","(1650,1475)","0","pure_quanta","I123";
;
PART_NUMBER"CH6103KEA00"
PACK_TYPE"C0805"
TOLERANCE"10%"
VOLTAGE"16V"
VALUE"10UF"
MATERIAL"X6S"
$LOCATION"C88"
CDS_LIB"pure_quanta"
$LOCATION"C88"
CDS_LOCATION"C88"
$SEC"1"
CDS_SEC"1";
"B"
$PN"2"6;
"A"
$PN"1"2;
%"VCC_CORE"
"1","(1650,1800)","0","logical_power","I124";
;
HDL_POWER"P12V_S3_AUX_CPU1_NVDIMM"
CDS_LIB"logical_power";
"A"2;
%"TAP"
"1","(1675,3400)","0","standard","I126";
;
CDS_LIB"standard"
BODY_TYPE"PLUMBING"
HDL_TAP"TRUE";
"B \NAC \NWC"16;
"S \NAC"
BN"0"66;
%"TAP"
"1","(1675,3500)","0","standard","I127";
;
CDS_LIB"standard"
BODY_TYPE"PLUMBING"
HDL_TAP"TRUE";
"B \NAC \NWC"16;
"S \NAC"
BN"1"67;
%"TAP"
"1","(1850,3350)","0","standard","I128";
;
CDS_LIB"standard"
BODY_TYPE"PLUMBING"
HDL_TAP"TRUE";
"B \NAC \NWC"18;
"S \NAC"
BN"0"46;
%"TAP"
"1","(1850,3450)","0","standard","I129";
;
CDS_LIB"standard"
BODY_TYPE"PLUMBING"
HDL_TAP"TRUE";
"B \NAC \NWC"18;
"S \NAC"
BN"1"48;
%"TAP"
"1","(1675,3600)","0","standard","I130";
;
CDS_LIB"standard"
BODY_TYPE"PLUMBING"
HDL_TAP"TRUE";
"B \NAC \NWC"16;
"S \NAC"
BN"2"65;
%"TAP"
"1","(1675,3700)","0","standard","I131";
;
CDS_LIB"standard"
BODY_TYPE"PLUMBING"
HDL_TAP"TRUE";
"B \NAC \NWC"16;
"S \NAC"
BN"3"64;
%"TAP"
"1","(1850,3550)","0","standard","I132";
;
CDS_LIB"standard"
BODY_TYPE"PLUMBING"
HDL_TAP"TRUE";
"B \NAC \NWC"18;
"S \NAC"
BN"2"47;
%"TAP"
"1","(1850,3750)","0","standard","I133";
;
CDS_LIB"standard"
BODY_TYPE"PLUMBING"
HDL_TAP"TRUE";
"B \NAC \NWC"18;
"S \NAC"
BN"4"44;
%"TAP"
"1","(1850,3650)","0","standard","I134";
;
CDS_LIB"standard"
BODY_TYPE"PLUMBING"
HDL_TAP"TRUE";
"B \NAC \NWC"18;
"S \NAC"
BN"3"45;
%"TAP"
"1","(1675,3800)","0","standard","I135";
;
CDS_LIB"standard"
BODY_TYPE"PLUMBING"
HDL_TAP"TRUE";
"B \NAC \NWC"16;
"S \NAC"
BN"4"63;
%"TAP"
"1","(1675,4000)","0","standard","I136";
;
CDS_LIB"standard"
BODY_TYPE"PLUMBING"
HDL_TAP"TRUE";
"B \NAC \NWC"16;
"S \NAC"
BN"6"61;
%"TAP"
"1","(1675,3900)","0","standard","I137";
;
CDS_LIB"standard"
BODY_TYPE"PLUMBING"
HDL_TAP"TRUE";
"B \NAC \NWC"16;
"S \NAC"
BN"5"62;
%"TAP"
"1","(1850,3850)","0","standard","I138";
;
CDS_LIB"standard"
BODY_TYPE"PLUMBING"
HDL_TAP"TRUE";
"B \NAC \NWC"18;
"S \NAC"
BN"5"43;
%"TAP"
"1","(1850,3950)","0","standard","I139";
;
CDS_LIB"standard"
BODY_TYPE"PLUMBING"
HDL_TAP"TRUE";
"B \NAC \NWC"18;
"S \NAC"
BN"6"42;
%"TAP"
"1","(1675,4100)","0","standard","I140";
;
CDS_LIB"standard"
BODY_TYPE"PLUMBING"
HDL_TAP"TRUE";
"B \NAC \NWC"16;
"S \NAC"
BN"7"60;
%"TAP"
"1","(1675,4200)","0","standard","I141";
;
CDS_LIB"standard"
BODY_TYPE"PLUMBING"
HDL_TAP"TRUE";
"B \NAC \NWC"16;
"S \NAC"
BN"8"28;
%"TAP"
"1","(1850,4050)","0","standard","I142";
;
CDS_LIB"standard"
BODY_TYPE"PLUMBING"
HDL_TAP"TRUE";
"B \NAC \NWC"18;
"S \NAC"
BN"7"41;
%"TAP"
"1","(1850,4150)","0","standard","I143";
;
CDS_LIB"standard"
BODY_TYPE"PLUMBING"
HDL_TAP"TRUE";
"B \NAC \NWC"18;
"S \NAC"
BN"8"29;
%"TAP"
"1","(1850,4250)","0","standard","I144";
;
CDS_LIB"standard"
BODY_TYPE"PLUMBING"
HDL_TAP"TRUE";
"B \NAC \NWC"18;
"S \NAC"
BN"9"40;
%"TAP"
"1","(1675,4300)","0","standard","I145";
;
CDS_LIB"standard"
BODY_TYPE"PLUMBING"
HDL_TAP"TRUE";
"B \NAC \NWC"16;
"S \NAC"
BN"9"59;
%"TAP"
"1","(1675,4450)","0","standard","I146";
;
CDS_LIB"standard"
BODY_TYPE"PLUMBING"
HDL_TAP"TRUE";
"B \NAC \NWC"17;
"S \NAC"
BN"0"57;
%"TAP"
"1","(1850,4400)","0","standard","I147";
;
CDS_LIB"standard"
BODY_TYPE"PLUMBING"
HDL_TAP"TRUE";
"B \NAC \NWC"19;
"S \NAC"
BN"0"37;
%"TAP"
"1","(1850,4500)","0","standard","I148";
;
CDS_LIB"standard"
BODY_TYPE"PLUMBING"
HDL_TAP"TRUE";
"B \NAC \NWC"19;
"S \NAC"
BN"1"38;
%"TAP"
"1","(1675,4650)","0","standard","I149";
;
CDS_LIB"standard"
BODY_TYPE"PLUMBING"
HDL_TAP"TRUE";
"B \NAC \NWC"17;
"S \NAC"
BN"2"56;
%"VCC_CORE"
"1","(-3550,3225)","0","logical_power","I15";
;
HDL_POWER"P3V3_AUX"
CDS_LIB"logical_power";
"A"4;
%"TAP"
"1","(1675,4550)","0","standard","I150";
;
CDS_LIB"standard"
BODY_TYPE"PLUMBING"
HDL_TAP"TRUE";
"B \NAC \NWC"17;
"S \NAC"
BN"1"58;
%"TAP"
"1","(1675,4750)","0","standard","I151";
;
CDS_LIB"standard"
BODY_TYPE"PLUMBING"
HDL_TAP"TRUE";
"B \NAC \NWC"17;
"S \NAC"
BN"3"55;
%"TAP"
"1","(1850,4600)","0","standard","I152";
;
CDS_LIB"standard"
BODY_TYPE"PLUMBING"
HDL_TAP"TRUE";
"B \NAC \NWC"19;
"S \NAC"
BN"2"39;
%"TAP"
"1","(1850,4700)","0","standard","I153";
;
CDS_LIB"standard"
BODY_TYPE"PLUMBING"
HDL_TAP"TRUE";
"B \NAC \NWC"19;
"S \NAC"
BN"3"36;
%"TAP"
"1","(1675,4850)","0","standard","I154";
;
CDS_LIB"standard"
BODY_TYPE"PLUMBING"
HDL_TAP"TRUE";
"B \NAC \NWC"17;
"S \NAC"
BN"4"54;
%"TAP"
"1","(1675,4950)","0","standard","I155";
;
CDS_LIB"standard"
BODY_TYPE"PLUMBING"
HDL_TAP"TRUE";
"B \NAC \NWC"17;
"S \NAC"
BN"5"52;
%"TAP"
"1","(1850,4900)","0","standard","I156";
;
CDS_LIB"standard"
BODY_TYPE"PLUMBING"
HDL_TAP"TRUE";
"B \NAC \NWC"19;
"S \NAC"
BN"5"34;
%"TAP"
"1","(1850,4800)","0","standard","I157";
;
CDS_LIB"standard"
BODY_TYPE"PLUMBING"
HDL_TAP"TRUE";
"B \NAC \NWC"19;
"S \NAC"
BN"4"35;
%"TAP"
"1","(1850,5000)","0","standard","I158";
;
CDS_LIB"standard"
BODY_TYPE"PLUMBING"
HDL_TAP"TRUE";
"B \NAC \NWC"19;
"S \NAC"
BN"6"33;
%"UNIVERSAL_GND"
"1","(2275,1100)","0","logical_power","I159";
;
HDL_POWER"GND"
CDS_LIB"logical_power";
"A"6;
%"Q_CAP"
"1","(2275,1475)","0","pure_quanta","I160";
;
PART_NUMBER"CH6103KEA00"
VALUE"10UF"
PACK_TYPE"C0805"
TOLERANCE"10%"
VOLTAGE"16V"
MATERIAL"X6S"
$LOCATION"C89"
CDS_LIB"pure_quanta"
$LOCATION"C89"
CDS_LOCATION"C89"
$SEC"1"
CDS_SEC"1";
"B"
$PN"2"6;
"A"
$PN"1"2;
%"UNIVERSAL_GND"
"1","(3350,1650)","0","logical_power","I161";
;
HDL_POWER"GND"
CDS_LIB"logical_power";
"A"7;
%"TAP"
"1","(1675,5150)","0","standard","I165";
;
CDS_LIB"standard"
BODY_TYPE"PLUMBING"
HDL_TAP"TRUE";
"B \NAC \NWC"17;
"S \NAC"
BN"7"49;
%"TAP"
"1","(1675,5050)","0","standard","I166";
;
CDS_LIB"standard"
BODY_TYPE"PLUMBING"
HDL_TAP"TRUE";
"B \NAC \NWC"17;
"S \NAC"
BN"6"53;
%"TAP"
"1","(1675,5250)","0","standard","I167";
;
CDS_LIB"standard"
BODY_TYPE"PLUMBING"
HDL_TAP"TRUE";
"B \NAC \NWC"17;
"S \NAC"
BN"8"50;
%"TAP"
"1","(1850,5100)","0","standard","I168";
;
CDS_LIB"standard"
BODY_TYPE"PLUMBING"
HDL_TAP"TRUE";
"B \NAC \NWC"19;
"S \NAC"
BN"7"32;
%"TAP"
"1","(1850,5200)","0","standard","I169";
;
CDS_LIB"standard"
BODY_TYPE"PLUMBING"
HDL_TAP"TRUE";
"B \NAC \NWC"19;
"S \NAC"
BN"8"31;
%"TAP"
"1","(1850,5300)","0","standard","I170";
;
CDS_LIB"standard"
BODY_TYPE"PLUMBING"
HDL_TAP"TRUE";
"B \NAC \NWC"19;
"S \NAC"
BN"9"30;
%"TAP"
"1","(1675,5350)","0","standard","I171";
;
CDS_LIB"standard"
BODY_TYPE"PLUMBING"
HDL_TAP"TRUE";
"B \NAC \NWC"17;
"S \NAC"
BN"9"51;
%"VCC_CORE"
"1","(3350,5900)","0","logical_power","I174";
;
HDL_POWER"P12V_S3_AUX_CPU1_NVDIMM"
CDS_LIB"logical_power";
"A"3;
%"UNIVERSAL_GND"
"1","(5050,1650)","0","logical_power","I175";
;
HDL_POWER"GND"
CDS_LIB"logical_power";
"A"8;
%"TAP"
"1","(-1075,2750)","0","standard","I176";
;
CDS_LIB"standard"
BODY_TYPE"PLUMBING"
HDL_TAP"TRUE";
"B \NAC \NWC"15;
"S \NAC"
BN"12"97;
%"SCONN288_ADR50017P130CC"
"3","(4200,3725)","0","pure_quanta","I178";
;
PART_NUMBER"DFHST8FS461"
MATERIAL"IO"
PART_TYPE"SMLF"
VALUE"SCONN288_ADR50017-P130CC"
$LOCATION"J27"
NEEDS_NO_SIZE"TRUE"
CDS_LMAN_SYM_OUTLINE"-450,1775,450,-1775"
CDS_LIB"pure_quanta"
CDS_LOCATION"J27"
$SEC"3"
CDS_SEC"3";
"G3"
$PN"G3"8;
"G2"
$PN"G2"8;
"G1"
$PN"G1"8;
"VSS62"
$PN"141"8;
"VSS61"
$PN"139"8;
"VSS60"
$PN"136"8;
"VSS58"
$PN"132"8;
"VSS104"
$PN"240"7;
"VSS102"
$PN"235"7;
"VSS100"
$PN"230"7;
"VIN_BULK2"
$PN"146"3;
"VIN_BULK1"
$PN"145"3;
"VIN_BULK0"
$PN"1"3;
"VSS126"
$PN"288"7;
"VSS125"
$PN"286"7;
"VSS124"
$PN"284"7;
"VSS123"
$PN"281"7;
"VSS122"
$PN"279"7;
"VSS121"
$PN"277"7;
"VSS120"
$PN"275"7;
"VSS119"
$PN"273"7;
"VSS118"
$PN"270"7;
"VSS117"
$PN"268"7;
"VSS116"
$PN"266"7;
"VSS115"
$PN"264"7;
"VSS114"
$PN"262"7;
"VSS113"
$PN"259"7;
"VSS112"
$PN"257"7;
"VSS111"
$PN"255"7;
"VSS110"
$PN"253"7;
"VSS109"
$PN"251"7;
"VSS108"
$PN"248"7;
"VSS107"
$PN"246"7;
"VSS106"
$PN"244"7;
"VSS105"
$PN"242"7;
"VSS103"
$PN"237"7;
"VSS101"
$PN"233"7;
"VSS99"
$PN"228"7;
"VSS98"
$PN"226"7;
"VSS97"
$PN"224"7;
"VSS96"
$PN"222"7;
"VSS95"
$PN"219"7;
"VSS94"
$PN"216"7;
"VSS93"
$PN"214"7;
"VSS92"
$PN"212"7;
"VSS91"
$PN"210"7;
"VSS90"
$PN"208"7;
"VSS89"
$PN"206"7;
"VSS88"
$PN"204"7;
"VSS87"
$PN"202"7;
"VSS86"
$PN"199"7;
"VSS85"
$PN"197"7;
"VSS84"
$PN"195"7;
"VSS83"
$PN"193"7;
"VSS82"
$PN"191"7;
"VSS81"
$PN"188"7;
"VSS80"
$PN"186"7;
"VSS79"
$PN"184"7;
"VSS78"
$PN"182"7;
"VSS77"
$PN"180"7;
"VSS76"
$PN"177"7;
"VSS75"
$PN"175"7;
"VSS74"
$PN"173"7;
"VSS73"
$PN"171"7;
"VSS72"
$PN"169"7;
"VSS71"
$PN"166"7;
"VSS70"
$PN"164"7;
"VSS69"
$PN"162"7;
"VSS68"
$PN"160"7;
"VSS67"
$PN"158"7;
"VSS66"
$PN"155"7;
"VSS65"
$PN"153"7;
"VSS64"
$PN"151"7;
"VSS63"
$PN"143"8;
"VSS59"
$PN"134"8;
"VSS57"
$PN"130"8;
"VSS56"
$PN"128"8;
"VSS55"
$PN"125"8;
"VSS54"
$PN"123"8;
"VSS53"
$PN"121"8;
"VSS52"
$PN"119"8;
"VSS51"
$PN"117"8;
"VSS50"
$PN"114"8;
"VSS49"
$PN"112"8;
"VSS48"
$PN"110"8;
"VSS47"
$PN"108"8;
"VSS46"
$PN"106"8;
"VSS45"
$PN"103"8;
"VSS44"
$PN"101"8;
"VSS43"
$PN"99"8;
"VSS42"
$PN"97"8;
"VSS41"
$PN"95"8;
"VSS40"
$PN"92"8;
"VSS39"
$PN"90"8;
"VSS38"
$PN"88"8;
"VSS37"
$PN"85"8;
"VSS36"
$PN"83"8;
"VSS35"
$PN"81"8;
"VSS34"
$PN"79"8;
"VSS33"
$PN"77"8;
"VSS32"
$PN"75"8;
"VSS31"
$PN"73"8;
"VSS30"
$PN"71"8;
"VSS29"
$PN"69"8;
"VSS28"
$PN"67"8;
"VSS27"
$PN"65"8;
"VSS26"
$PN"63"8;
"VSS25"
$PN"61"8;
"VSS24"
$PN"59"8;
"VSS23"
$PN"57"8;
"VSS22"
$PN"54"8;
"VSS21"
$PN"52"8;
"VSS20"
$PN"50"8;
"VSS19"
$PN"48"8;
"VSS18"
$PN"46"8;
"VSS17"
$PN"43"8;
"VSS16"
$PN"41"8;
"VSS15"
$PN"39"8;
"VSS14"
$PN"37"8;
"VSS13"
$PN"35"8;
"VSS12"
$PN"32"8;
"VSS11"
$PN"30"8;
"VSS10"
$PN"28"8;
"VSS9"
$PN"26"8;
"VSS8"
$PN"24"8;
"VSS7"
$PN"21"8;
"VSS6"
$PN"19"8;
"VSS5"
$PN"17"8;
"VSS4"
$PN"15"8;
"VSS3"
$PN"13"8;
"VSS2"
$PN"10"8;
"VSS1"
$PN"8"8;
"VSS0"
$PN"6"8;
%"SCONN288_ADR50017P130CC"
"1","(-1900,3625)","0","pure_quanta","I179";
;
PART_NUMBER"DFHST8FS461"
MATERIAL"IO"
PART_TYPE"SMLF"
VALUE"SCONN288_ADR50017-P130CC"
$LOCATION"J27"
NEEDS_NO_SIZE"TRUE"
CDS_LMAN_SYM_OUTLINE"-450,1875,450,-1875"
CDS_LIB"pure_quanta"
CDS_LOCATION"J27"
$SEC"1"
CDS_SEC"1";
"DQ31_A"
$PN"194"177;
"CB7_A"
$PN"205"176;
"CB4_A"
$PN"58"175;
"CB1_A"
$PN"53"68;
"CB7_B"
$PN"236"74;
"ALERT_N \B"
$PN"62"24;
"CA0_A"
$PN"66"174;
"CA0_B"
$PN"76"173;
"CA1_A"
$PN"211"172;
"CA1_B"
$PN"221"171;
"CA2_A"
$PN"68"170;
"CA2_B"
$PN"78"169;
"CA3_A"
$PN"213"168;
"CA3_B"
$PN"223"167;
"CA4_A"
$PN"70"166;
"CA4_B"
$PN"80"165;
"CA5_A"
$PN"215"164;
"CA5_B"
$PN"225"163;
"CA6_A"
$PN"72"162;
"CA6_B"
$PN"82"161;
"CB6_A"
$PN"203"160;
"CB5_A"
$PN"60"159;
"CB3_A"
$PN"198"158;
"CB2_A"
$PN"196"157;
"CB0_A"
$PN"51"156;
"CB6_B"
$PN"234"155;
"CB5_B"
$PN"91"154;
"CB4_B"
$PN"89"153;
"CB3_B"
$PN"243"152;
"CB2_B"
$PN"241"151;
"CB1_B"
$PN"98"150;
"CB0_B"
$PN"96"149;
"CK_C \B"
$PN"218"148;
"CK_T"
$PN"217"147;
"CS0_A_N"
$PN"64"146;
"CS0_B_N"
$PN"84"145;
"CS1_A_N"
$PN"209"144;
"CS1_B_N"
$PN"229"143;
"DQ30_A"
$PN"192"142;
"DQ29_A"
$PN"49"141;
"DQ28_A"
$PN"47"76;
"DQ27_A"
$PN"187"140;
"DQ26_A"
$PN"185"139;
"DQ25_A"
$PN"42"138;
"DQ24_A"
$PN"40"137;
"DQ23_A"
$PN"183"136;
"DQ22_A"
$PN"181"135;
"DQ21_A"
$PN"38"134;
"DQ20_A"
$PN"36"77;
"DQ19_A"
$PN"176"78;
"DQ18_A"
$PN"174"133;
"DQ17_A"
$PN"31"132;
"DQ16_A"
$PN"29"131;
"DQ15_A"
$PN"172"130;
"DQ14_A"
$PN"170"129;
"DQ13_A"
$PN"27"75;
"DQ12_A"
$PN"25"128;
"DQ11_A"
$PN"165"127;
"DQ10_A"
$PN"163"126;
"DQ9_A"
$PN"20"125;
"DQ8_A"
$PN"18"124;
"DQ7_A"
$PN"161"123;
"DQ6_A"
$PN"159"122;
"DQ5_A"
$PN"16"121;
"DQ4_A"
$PN"14"120;
"DQ3_A"
$PN"154"119;
"DQ2_A"
$PN"152"118;
"DQ1_A"
$PN"9"117;
"DQ0_A"
$PN"7"116;
"DQ31_B"
$PN"287"115;
"DQ30_B"
$PN"285"114;
"DQ29_B"
$PN"142"113;
"DQ28_B"
$PN"140"112;
"DQ27_B"
$PN"280"111;
"DQ26_B"
$PN"278"110;
"DQ25_B"
$PN"135"109;
"DQ24_B"
$PN"133"108;
"DQ23_B"
$PN"276"107;
"DQ22_B"
$PN"274"106;
"DQ21_B"
$PN"131"105;
"DQ20_B"
$PN"129"104;
"DQ19_B"
$PN"269"103;
"DQ18_B"
$PN"267"102;
"DQ17_B"
$PN"124"79;
"DQ16_B"
$PN"122"101;
"DQ15_B"
$PN"265"100;
"DQ14_B"
$PN"263"99;
"DQ13_B"
$PN"120"98;
"DQ12_B"
$PN"118"97;
"DQ11_B"
$PN"258"96;
"DQ10_B"
$PN"256"95;
"DQ9_B"
$PN"113"94;
"DQ8_B"
$PN"111"93;
"DQ7_B"
$PN"254"92;
"DQ6_B"
$PN"252"91;
"DQ5_B"
$PN"109"90;
"DQ4_B"
$PN"107"89;
"DQ3_B"
$PN"247"88;
"DQ2_B"
$PN"245"87;
"DQ1_B"
$PN"102"86;
"DQ0_B"
$PN"100"85;
"HSA"
$PN"148"22;
"HSCL"
$PN"4"21;
"HSDA"
$PN"5"20;
"LBD||RSP_A_N"
$PN"86"71;
"LBS||RSP_B_N"
$PN"87"84;
"PAR_A"
$PN"74"83;
"PAR_B"
$PN"227"82;
"PWR_GOOD||FAIL_N"
$PN"147"26;
"RESET_N \B"
$PN"207"23;
"RFU6"
$PN"232"27;
"RFU5"
$PN"231"73;
"RFU4"
$PN"220"81;
"RFU3"
$PN"150"70;
"RFU2"
$PN"149"80;
"RFU1"
$PN"144"69;
"RFU0"
$PN"2"72;
"VIN_MGMT"
$PN"3"4;
%"SCONN288_ADR50017P130CC"
"2","(775,4350)","0","pure_quanta","I180";
;
PART_NUMBER"DFHST8FS461"
MATERIAL"IO"
PART_TYPE"SMLF"
VALUE"SCONN288_ADR50017-P130CC"
LOCATION"J27"
NEEDS_NO_SIZE"TRUE"
CDS_LMAN_SYM_OUTLINE"-600,1150,600,-1150"
CDS_LIB"pure_quanta"
$SEC"2"
CDS_SEC"2";
"DQS7_A_C||TDQS7_A_C \B"
$PN"178"32;
"DQS6_A_T||TDQS6_A_T"
$PN"168"53;
"DQS8_B_T||TDQS8_B_T"
$PN"283"28;
"DQS8_B_C||TDQS8_B_C \B"
$PN"282"29;
"DQS7_B_T||TDQS7_B_T"
$PN"272"60;
"DQS0_A_C \B"
$PN"12"37;
"DQS0_A_T"
$PN"11"57;
"DQS0_B_C \B"
$PN"105"46;
"DQS0_B_T"
$PN"104"66;
"DQS1_A_C \B"
$PN"23"38;
"DQS1_A_T"
$PN"22"58;
"DQS1_B_C \B"
$PN"116"48;
"DQS1_B_T"
$PN"115"67;
"DQS2_A_C \B"
$PN"34"39;
"DQS2_A_T"
$PN"33"56;
"DQS2_B_C \B"
$PN"127"47;
"DQS2_B_T"
$PN"126"65;
"DQS3_A_C \B"
$PN"45"36;
"DQS3_A_T"
$PN"44"55;
"DQS3_B_C \B"
$PN"138"45;
"DQS3_B_T"
$PN"137"64;
"DQS4_A_C \B"
$PN"56"35;
"DQS4_A_T"
$PN"55"54;
"DQS4_B_C \B"
$PN"238"44;
"DQS4_B_T"
$PN"239"63;
"DQS5_A_C||TDQS5_A_C||DQS5_A_T||TDQS5_A_T \B"
$PN"156"34;
"DQS5_A_T||TDQS5_A_T"
$PN"157"52;
"DQS5_B_C||TDQS5_B_C \B"
$PN"249"43;
"DQS5_B_T||TDQS5_B_T"
$PN"250"62;
"DQS6_A_C||TDQS6_A_C||DQS6_A_T||TDQS6_A_T \B"
$PN"167"33;
"DQS6_B_C||TDQS6_B_C \B"
$PN"260"42;
"DQS6_B_T||TDQS6_B_T"
$PN"261"61;
"DQS7_A_T||TDQS7_A_T"
$PN"179"49;
"DQS7_B_C||TDQS7_B_C \B"
$PN"271"41;
"DQS8_A_C||TDQS8_A_C \B"
$PN"189"31;
"DQS8_A_T||TDQS8_A_T"
$PN"190"50;
"DQS9_A_C||TDQS9_A_C \B"
$PN"200"30;
"DQS9_A_T||TDQS9_A_T"
$PN"201"51;
"DQS9_B_C||TDQS9_B_C \B"
$PN"94"40;
"DQS9_B_T||TDQS9_B_T||DBI4_B_N"
$PN"93"59;
%"Q_RES"
"1","(-3700,2675)","0","pure_quanta","I182";
;
PART_NUMBER"CS04992FB07"
TOLERANCE"1%"
MATERIAL"CHIP"
VALUE"49.9"
$LOCATION"R3901"
CDS_LIB"pure_quanta"
PACK_TYPE"0402LF"
WATTAGE"1/16W"
CDS_LOCATION"R3901"
$SEC"1"
CDS_SEC"1";
"B"
$PN"2"25;
"A"
$PN"1"21;
%"TAP"
"1","(-2725,3150)","2","standard","I24";
;
CDS_LIB"standard"
BODY_TYPE"PLUMBING"
HDL_TAP"TRUE";
"B \NAC \NWC"14;
"S \NAC"
BN"0"149;
%"TAP"
"1","(-2725,3200)","2","standard","I25";
;
CDS_LIB"standard"
BODY_TYPE"PLUMBING"
HDL_TAP"TRUE";
"B \NAC \NWC"14;
"S \NAC"
BN"1"150;
%"TAP"
"1","(-2725,3250)","2","standard","I26";
;
CDS_LIB"standard"
BODY_TYPE"PLUMBING"
HDL_TAP"TRUE";
"B \NAC \NWC"14;
"S \NAC"
BN"2"151;
%"TAP"
"1","(-2725,3300)","2","standard","I27";
;
CDS_LIB"standard"
BODY_TYPE"PLUMBING"
HDL_TAP"TRUE";
"B \NAC \NWC"14;
"S \NAC"
BN"3"152;
%"TAP"
"1","(-2725,3350)","2","standard","I28";
;
CDS_LIB"standard"
BODY_TYPE"PLUMBING"
HDL_TAP"TRUE";
"B \NAC \NWC"14;
"S \NAC"
BN"4"153;
%"TAP"
"1","(-2725,3450)","2","standard","I29";
;
CDS_LIB"standard"
BODY_TYPE"PLUMBING"
HDL_TAP"TRUE";
"B \NAC \NWC"14;
"S \NAC"
BN"6"155;
%"TAP"
"1","(-2725,3400)","2","standard","I30";
;
CDS_LIB"standard"
BODY_TYPE"PLUMBING"
HDL_TAP"TRUE";
"B \NAC \NWC"14;
"S \NAC"
BN"5"154;
%"TAP"
"1","(-2725,3500)","2","standard","I31";
;
CDS_LIB"standard"
BODY_TYPE"PLUMBING"
HDL_TAP"TRUE";
"B \NAC \NWC"14;
"S \NAC"
BN"7"74;
%"TAP"
"1","(-2725,3600)","2","standard","I32";
;
CDS_LIB"standard"
BODY_TYPE"PLUMBING"
HDL_TAP"TRUE";
"B \NAC \NWC"11;
"S \NAC"
BN"0"156;
%"TAP"
"1","(-2725,3650)","2","standard","I33";
;
CDS_LIB"standard"
BODY_TYPE"PLUMBING"
HDL_TAP"TRUE";
"B \NAC \NWC"11;
"S \NAC"
BN"1"68;
%"TAP"
"1","(-2725,3700)","2","standard","I34";
;
CDS_LIB"standard"
BODY_TYPE"PLUMBING"
HDL_TAP"TRUE";
"B \NAC \NWC"11;
"S \NAC"
BN"2"157;
%"TAP"
"1","(-2725,3750)","2","standard","I35";
;
CDS_LIB"standard"
BODY_TYPE"PLUMBING"
HDL_TAP"TRUE";
"B \NAC \NWC"11;
"S \NAC"
BN"3"158;
%"TAP"
"1","(-2725,3850)","2","standard","I36";
;
CDS_LIB"standard"
BODY_TYPE"PLUMBING"
HDL_TAP"TRUE";
"B \NAC \NWC"11;
"S \NAC"
BN"5"159;
%"TAP"
"1","(-2725,3800)","2","standard","I37";
;
CDS_LIB"standard"
BODY_TYPE"PLUMBING"
HDL_TAP"TRUE";
"B \NAC \NWC"11;
"S \NAC"
BN"4"175;
%"TAP"
"1","(-2725,3950)","2","standard","I38";
;
CDS_LIB"standard"
BODY_TYPE"PLUMBING"
HDL_TAP"TRUE";
"B \NAC \NWC"11;
"S \NAC"
BN"7"176;
%"TAP"
"1","(-2725,3900)","2","standard","I39";
;
CDS_LIB"standard"
BODY_TYPE"PLUMBING"
HDL_TAP"TRUE";
"B \NAC \NWC"11;
"S \NAC"
BN"6"160;
%"TAP"
"1","(-2725,4650)","2","standard","I40";
;
CDS_LIB"standard"
BODY_TYPE"PLUMBING"
HDL_TAP"TRUE";
"B \NAC \NWC"13;
"S \NAC"
BN"0"173;
%"TAP"
"1","(-2725,4700)","2","standard","I41";
;
CDS_LIB"standard"
BODY_TYPE"PLUMBING"
HDL_TAP"TRUE";
"B \NAC \NWC"13;
"S \NAC"
BN"1"171;
%"TAP"
"1","(-2725,4750)","2","standard","I42";
;
CDS_LIB"standard"
BODY_TYPE"PLUMBING"
HDL_TAP"TRUE";
"B \NAC \NWC"13;
"S \NAC"
BN"2"169;
%"TAP"
"1","(-2725,4800)","2","standard","I43";
;
CDS_LIB"standard"
BODY_TYPE"PLUMBING"
HDL_TAP"TRUE";
"B \NAC \NWC"13;
"S \NAC"
BN"3"167;
%"TAP"
"1","(-2725,4850)","2","standard","I44";
;
CDS_LIB"standard"
BODY_TYPE"PLUMBING"
HDL_TAP"TRUE";
"B \NAC \NWC"13;
"S \NAC"
BN"4"165;
%"TAP"
"1","(-2725,4900)","2","standard","I45";
;
CDS_LIB"standard"
BODY_TYPE"PLUMBING"
HDL_TAP"TRUE";
"B \NAC \NWC"13;
"S \NAC"
BN"5"163;
%"TAP"
"1","(-2725,4950)","2","standard","I46";
;
CDS_LIB"standard"
BODY_TYPE"PLUMBING"
HDL_TAP"TRUE";
"B \NAC \NWC"13;
"S \NAC"
BN"6"161;
%"TAP"
"1","(-1075,2200)","0","standard","I47";
;
CDS_LIB"standard"
BODY_TYPE"PLUMBING"
HDL_TAP"TRUE";
"B \NAC \NWC"15;
"S \NAC"
BN"1"86;
%"TAP"
"1","(-1075,2150)","0","standard","I48";
;
CDS_LIB"standard"
BODY_TYPE"PLUMBING"
HDL_TAP"TRUE";
"B \NAC \NWC"15;
"S \NAC"
BN"0"85;
%"TAP"
"1","(-1075,2250)","0","standard","I49";
;
CDS_LIB"standard"
BODY_TYPE"PLUMBING"
HDL_TAP"TRUE";
"B \NAC \NWC"15;
"S \NAC"
BN"2"87;
%"TAP"
"1","(-1075,2350)","0","standard","I50";
;
CDS_LIB"standard"
BODY_TYPE"PLUMBING"
HDL_TAP"TRUE";
"B \NAC \NWC"15;
"S \NAC"
BN"4"89;
%"TAP"
"1","(-1075,2300)","0","standard","I51";
;
CDS_LIB"standard"
BODY_TYPE"PLUMBING"
HDL_TAP"TRUE";
"B \NAC \NWC"15;
"S \NAC"
BN"3"88;
%"TAP"
"1","(-1075,2450)","0","standard","I52";
;
CDS_LIB"standard"
BODY_TYPE"PLUMBING"
HDL_TAP"TRUE";
"B \NAC \NWC"15;
"S \NAC"
BN"6"91;
%"TAP"
"1","(-1075,2400)","0","standard","I53";
;
CDS_LIB"standard"
BODY_TYPE"PLUMBING"
HDL_TAP"TRUE";
"B \NAC \NWC"15;
"S \NAC"
BN"5"90;
%"TAP"
"1","(-1075,2500)","0","standard","I54";
;
CDS_LIB"standard"
BODY_TYPE"PLUMBING"
HDL_TAP"TRUE";
"B \NAC \NWC"15;
"S \NAC"
BN"7"92;
%"TAP"
"1","(-1075,2550)","0","standard","I55";
;
CDS_LIB"standard"
BODY_TYPE"PLUMBING"
HDL_TAP"TRUE";
"B \NAC \NWC"15;
"S \NAC"
BN"8"93;
%"TAP"
"1","(-1075,2600)","0","standard","I56";
;
CDS_LIB"standard"
BODY_TYPE"PLUMBING"
HDL_TAP"TRUE";
"B \NAC \NWC"15;
"S \NAC"
BN"9"94;
%"TAP"
"1","(-1075,2700)","0","standard","I57";
;
CDS_LIB"standard"
BODY_TYPE"PLUMBING"
HDL_TAP"TRUE";
"B \NAC \NWC"15;
"S \NAC"
BN"11"96;
%"TAP"
"1","(-1075,2650)","0","standard","I58";
;
CDS_LIB"standard"
BODY_TYPE"PLUMBING"
HDL_TAP"TRUE";
"B \NAC \NWC"15;
"S \NAC"
BN"10"95;
%"TAP"
"1","(-1075,2800)","0","standard","I59";
;
CDS_LIB"standard"
BODY_TYPE"PLUMBING"
HDL_TAP"TRUE";
"B \NAC \NWC"15;
"S \NAC"
BN"13"98;
%"TAP"
"1","(-1075,2850)","0","standard","I60";
;
CDS_LIB"standard"
BODY_TYPE"PLUMBING"
HDL_TAP"TRUE";
"B \NAC \NWC"15;
"S \NAC"
BN"14"99;
%"TAP"
"1","(-1075,2950)","0","standard","I61";
;
CDS_LIB"standard"
BODY_TYPE"PLUMBING"
HDL_TAP"TRUE";
"B \NAC \NWC"15;
"S \NAC"
BN"16"101;
%"TAP"
"1","(-1075,2900)","0","standard","I62";
;
CDS_LIB"standard"
BODY_TYPE"PLUMBING"
HDL_TAP"TRUE";
"B \NAC \NWC"15;
"S \NAC"
BN"15"100;
%"TAP"
"1","(-1075,3000)","0","standard","I63";
;
CDS_LIB"standard"
BODY_TYPE"PLUMBING"
HDL_TAP"TRUE";
"B \NAC \NWC"15;
"S \NAC"
BN"17"79;
%"TAP"
"1","(-1075,3050)","0","standard","I64";
;
CDS_LIB"standard"
BODY_TYPE"PLUMBING"
HDL_TAP"TRUE";
"B \NAC \NWC"15;
"S \NAC"
BN"18"102;
%"TAP"
"1","(-1075,3100)","0","standard","I65";
;
CDS_LIB"standard"
BODY_TYPE"PLUMBING"
HDL_TAP"TRUE";
"B \NAC \NWC"15;
"S \NAC"
BN"19"103;
%"TAP"
"1","(-1075,3150)","0","standard","I66";
;
CDS_LIB"standard"
BODY_TYPE"PLUMBING"
HDL_TAP"TRUE";
"B \NAC \NWC"15;
"S \NAC"
BN"20"104;
%"TAP"
"1","(-1075,3250)","0","standard","I67";
;
CDS_LIB"standard"
BODY_TYPE"PLUMBING"
HDL_TAP"TRUE";
"B \NAC \NWC"15;
"S \NAC"
BN"22"106;
%"TAP"
"1","(-1075,3200)","0","standard","I68";
;
CDS_LIB"standard"
BODY_TYPE"PLUMBING"
HDL_TAP"TRUE";
"B \NAC \NWC"15;
"S \NAC"
BN"21"105;
%"TAP"
"1","(-1075,3350)","0","standard","I69";
;
CDS_LIB"standard"
BODY_TYPE"PLUMBING"
HDL_TAP"TRUE";
"B \NAC \NWC"15;
"S \NAC"
BN"24"108;
%"TAP"
"1","(-1075,3300)","0","standard","I70";
;
CDS_LIB"standard"
BODY_TYPE"PLUMBING"
HDL_TAP"TRUE";
"B \NAC \NWC"15;
"S \NAC"
BN"23"107;
%"TAP"
"1","(-1075,3400)","0","standard","I71";
;
CDS_LIB"standard"
BODY_TYPE"PLUMBING"
HDL_TAP"TRUE";
"B \NAC \NWC"15;
"S \NAC"
BN"25"109;
%"TAP"
"1","(-1075,3450)","0","standard","I72";
;
CDS_LIB"standard"
BODY_TYPE"PLUMBING"
HDL_TAP"TRUE";
"B \NAC \NWC"15;
"S \NAC"
BN"26"110;
%"TAP"
"1","(-1075,3500)","0","standard","I73";
;
CDS_LIB"standard"
BODY_TYPE"PLUMBING"
HDL_TAP"TRUE";
"B \NAC \NWC"15;
"S \NAC"
BN"27"111;
%"TAP"
"1","(-1075,3600)","0","standard","I74";
;
CDS_LIB"standard"
BODY_TYPE"PLUMBING"
HDL_TAP"TRUE";
"B \NAC \NWC"15;
"S \NAC"
BN"29"113;
%"TAP"
"1","(-1075,3550)","0","standard","I75";
;
CDS_LIB"standard"
BODY_TYPE"PLUMBING"
HDL_TAP"TRUE";
"B \NAC \NWC"15;
"S \NAC"
BN"28"112;
%"TAP"
"1","(-1075,3700)","0","standard","I76";
;
CDS_LIB"standard"
BODY_TYPE"PLUMBING"
HDL_TAP"TRUE";
"B \NAC \NWC"15;
"S \NAC"
BN"31"115;
%"TAP"
"1","(-1075,3650)","0","standard","I77";
;
CDS_LIB"standard"
BODY_TYPE"PLUMBING"
HDL_TAP"TRUE";
"B \NAC \NWC"15;
"S \NAC"
BN"30"114;
%"TAP"
"1","(-1075,3800)","0","standard","I78";
;
CDS_LIB"standard"
BODY_TYPE"PLUMBING"
HDL_TAP"TRUE";
"B \NAC \NWC"10;
"S \NAC"
BN"0"116;
%"TAP"
"1","(-1075,3850)","0","standard","I79";
;
CDS_LIB"standard"
BODY_TYPE"PLUMBING"
HDL_TAP"TRUE";
"B \NAC \NWC"10;
"S \NAC"
BN"1"117;
%"TAP"
"1","(-1075,3950)","0","standard","I80";
;
CDS_LIB"standard"
BODY_TYPE"PLUMBING"
HDL_TAP"TRUE";
"B \NAC \NWC"10;
"S \NAC"
BN"3"119;
%"TAP"
"1","(-1075,3900)","0","standard","I81";
;
CDS_LIB"standard"
BODY_TYPE"PLUMBING"
HDL_TAP"TRUE";
"B \NAC \NWC"10;
"S \NAC"
BN"2"118;
%"TAP"
"1","(-1075,4000)","0","standard","I82";
;
CDS_LIB"standard"
BODY_TYPE"PLUMBING"
HDL_TAP"TRUE";
"B \NAC \NWC"10;
"S \NAC"
BN"4"120;
%"TAP"
"1","(-1075,4100)","0","standard","I83";
;
CDS_LIB"standard"
BODY_TYPE"PLUMBING"
HDL_TAP"TRUE";
"B \NAC \NWC"10;
"S \NAC"
BN"6"122;
%"TAP"
"1","(-1075,4050)","0","standard","I84";
;
CDS_LIB"standard"
BODY_TYPE"PLUMBING"
HDL_TAP"TRUE";
"B \NAC \NWC"10;
"S \NAC"
BN"5"121;
%"TAP"
"1","(-1075,4150)","0","standard","I85";
;
CDS_LIB"standard"
BODY_TYPE"PLUMBING"
HDL_TAP"TRUE";
"B \NAC \NWC"10;
"S \NAC"
BN"7"123;
%"TAP"
"1","(-1075,4250)","0","standard","I86";
;
CDS_LIB"standard"
BODY_TYPE"PLUMBING"
HDL_TAP"TRUE";
"B \NAC \NWC"10;
"S \NAC"
BN"9"125;
%"TAP"
"1","(-1075,4200)","0","standard","I87";
;
CDS_LIB"standard"
BODY_TYPE"PLUMBING"
HDL_TAP"TRUE";
"B \NAC \NWC"10;
"S \NAC"
BN"8"124;
%"TAP"
"1","(-1075,4300)","0","standard","I88";
;
CDS_LIB"standard"
BODY_TYPE"PLUMBING"
HDL_TAP"TRUE";
"B \NAC \NWC"10;
"S \NAC"
BN"10"126;
%"TAP"
"1","(-1075,4350)","0","standard","I89";
;
CDS_LIB"standard"
BODY_TYPE"PLUMBING"
HDL_TAP"TRUE";
"B \NAC \NWC"10;
"S \NAC"
BN"11"127;
%"UNIVERSAL_GND"
"1","(-2500,975)","0","logical_power","I9";
;
HDL_POWER"GND"
CDS_LIB"logical_power";
"A"9;
%"TAP"
"1","(-1075,4400)","0","standard","I90";
;
CDS_LIB"standard"
BODY_TYPE"PLUMBING"
HDL_TAP"TRUE";
"B \NAC \NWC"10;
"S \NAC"
BN"12"128;
%"TAP"
"1","(-1075,4500)","0","standard","I91";
;
CDS_LIB"standard"
BODY_TYPE"PLUMBING"
HDL_TAP"TRUE";
"B \NAC \NWC"10;
"S \NAC"
BN"14"129;
%"TAP"
"1","(-1075,4450)","0","standard","I92";
;
CDS_LIB"standard"
BODY_TYPE"PLUMBING"
HDL_TAP"TRUE";
"B \NAC \NWC"10;
"S \NAC"
BN"13"75;
%"TAP"
"1","(-1075,4550)","0","standard","I93";
;
CDS_LIB"standard"
BODY_TYPE"PLUMBING"
HDL_TAP"TRUE";
"B \NAC \NWC"10;
"S \NAC"
BN"15"130;
%"TAP"
"1","(-1075,4600)","0","standard","I94";
;
CDS_LIB"standard"
BODY_TYPE"PLUMBING"
HDL_TAP"TRUE";
"B \NAC \NWC"10;
"S \NAC"
BN"16"131;
%"TAP"
"1","(-1075,4650)","0","standard","I95";
;
CDS_LIB"standard"
BODY_TYPE"PLUMBING"
HDL_TAP"TRUE";
"B \NAC \NWC"10;
"S \NAC"
BN"17"132;
%"TAP"
"1","(-1075,4750)","0","standard","I96";
;
CDS_LIB"standard"
BODY_TYPE"PLUMBING"
HDL_TAP"TRUE";
"B \NAC \NWC"10;
"S \NAC"
BN"19"78;
%"TAP"
"1","(-1075,4700)","0","standard","I97";
;
CDS_LIB"standard"
BODY_TYPE"PLUMBING"
HDL_TAP"TRUE";
"B \NAC \NWC"10;
"S \NAC"
BN"18"133;
%"TAP"
"1","(-1075,4800)","0","standard","I98";
;
CDS_LIB"standard"
BODY_TYPE"PLUMBING"
HDL_TAP"TRUE";
"B \NAC \NWC"10;
"S \NAC"
BN"20"77;
%"TAP"
"1","(-1075,4850)","0","standard","I99";
;
CDS_LIB"standard"
BODY_TYPE"PLUMBING"
HDL_TAP"TRUE";
"B \NAC \NWC"10;
"S \NAC"
BN"21"134;
END.
